FILE_TYPE = CONNECTIVITY;
{Allegro Design Entry HDL 17.2-2016 S081 (4005846) 1/11/2022}
"PAGE_NUMBER" = 177;
0"NC";
1"P3V3_RTC_AUX\g";
2"P3V_BAT_R";
3"P3V3_AUX\g";
4"P3V3_RTC_AUX\g";
5"P3V3_AUX\g";
6"GND\g";
7"GND\g";
8"GND\g";
9"GND\g";
10"GND\g";
11"GND\g";
12"GND\g";
13"RST_PFR_OVR_SRTC"CDS_PHYS_NET_NAME"FM_PCH_CRASHLOG_TRIG_R_N";
14"RST_PFR_OVR_RTC"CDS_PHYS_NET_NAME"FM_PCH_CRASHLOG_TRIG_R_N";
15"RST_SRTCRST_N";
16"SPI_PCH_IO3";
17"SPI_PCH_CLK";
18"SPI_PCH_IO2";
19"SPI_SYS_WP_IO2";
20"SPI_SYS_HOLD_IO3";
21"SPI_SYS_MISO";
22"SPI_SYS_MOSI";
23"SPI_SYS_CLK";
24"SPI_PCH_IO1";
25"SPI_PCH_IO0";
26"SPI_PCH_CS0_R_N";
27"P3V_BAT";
28"RST_RTCRST_N";
29"SPI_PCH_IO3";
30"SPI_PCH_IO1";
31"FM_XTAL_INPUT_FREQUENCY_0_MGPIO_TEST4"CDS_PHYS_NET_NAME"SPI_PCH_TPM_CS_N";
32"FM_PCH_SPKR"CDS_PHYS_NET_NAME"SPI_PCH_TPM_CS_N";
33"FM_XTAL_INPUT_FREQUENCY_1_MGPIO_TEST5"CDS_PHYS_NET_NAME"SPI_PCH_TPM_CS_N";
34"FM_ADR_MODE0"CDS_PHYS_NET_NAME"SPI_PCH_TPM_CS_N";
35"FM_SPI_3V3_1V8_VOLTAGE"CDS_PHYS_NET_NAME"SPI_PCH_TPM_CS_N";
36"FM_PCH_CONSENT_STRAP_N"CDS_PHYS_NET_NAME"SPI_PCH_TPM_CS_N";
37"SPI_PCH_CLK"CDS_PHYS_NET_NAME"SPI_PCH_TPM_CS_N";
38"TP_SPI_PCH_CS1_R_N"CDS_PHYS_NET_NAME"TP_SPI_PCH_CS1_N";
39"SPI_PCH_TPM_CS_N"CDS_PHYS_NET_NAME"SPI_PCH_TPM_CS_N";
40"RST_RTCRST_N";
41"SPI_PCH_IO0";
42"SPI_PCH_CS0_R_N"CDS_PHYS_NET_NAME"TP_SPI_PCH_CS1_N";
43"SPI_PCH_IO2";
44"RST_SRTCRST_N";
45"SPI_PCH_TPM_CS_N";
46"FM_EUP_LOT6_N"CDS_PHYS_NET_NAME"FM_PCH_CRASHLOG_TRIG_R_N";
47"SPI_TPM_CS_N";
48"SPI_SYS_CS0_N";
49"FM_SUSACK_N"CDS_PHYS_NET_NAME"FM_PCH_CRASHLOG_TRIG_N";
50"TP_PCH_GPP_N_1"CDS_PHYS_NET_NAME"FM_PCH_SLP_S4_N";
51"TP_PCH_GPP_N_4"CDS_PHYS_NET_NAME"FM_PCH_SLP_S4_N";
52"TP_PCH_CGC_DUT_DETECTED"CDS_PHYS_NET_NAME"SPI_PCH_TPM_CS_N";
53"FM_PCH_PRSNT_N"CDS_PHYS_NET_NAME"SPI_PCH_TPM_CS_N";
54"RST_SRTCRST_N";
55"FM_ESPI_CS_SWIZZLE"CDS_PHYS_NET_NAME"SPI_PCH_TPM_CS_N";
56"FM_JTAG_ODT_DISABLE"CDS_PHYS_NET_NAME"SPI_PCH_TPM_CS_N";
57"IRQ_SMI_ACTIVE_N"CDS_PHYS_NET_NAME"SPI_PCH_TPM_CS_N";
58"IRQ_PCH_CPU_NMI_EVENT_R_N"CDS_PHYS_NET_NAME"SPI_PCH_TPM_CS_N";
59"FM_SUSACK_N"CDS_PHYS_NET_NAME"SPI_PCH_TPM_CS_N";
60"FM_EUP_LOT6_N"CDS_PHYS_NET_NAME"SPI_PCH_TPM_CS_N";
%"Q_RES"
"1","(4225,-750)","0","pure_quanta","I100";
;
PART_NUMBER"CS03322FB03"
VALUE"33.2"
PACK_TYPE"0402LF"
MATERIAL"CHIP"
WATTAGE"1/16W"
TOLERANCE"1%"
$LOCATION"R501"
CDS_LIB"pure_quanta"
CDS_LOCATION"R501"
$SEC"1"
CDS_SEC"1";
"B"
$PN"2"48;
"A"
$PN"1"26;
%"Q_RES"
"1","(4225,-900)","0","pure_quanta","I102";
;
PART_NUMBER"CS03322FB03"
MATERIAL"CHIP"
TOLERANCE"1%"
VALUE"33.2"
$LOCATION"R1395"
CDS_LIB"pure_quanta"
PACK_TYPE"0402LF"
WATTAGE"1/16W"
CDS_LOCATION"R1395"
$SEC"1"
CDS_SEC"1";
"B"
$PN"2"47;
"A"
$PN"1"45;
%"Q_RES"
"1","(4200,-1475)","0","pure_quanta","I106";
;
PART_NUMBER"CS03322FB03"
VALUE"33.2"
MATERIAL"CHIP"
TOLERANCE"1%"
$LOCATION"R499"
CDS_LIB"pure_quanta"
PACK_TYPE"0402LF"
WATTAGE"1/16W"
CDS_LOCATION"R499"
$SEC"1"
CDS_SEC"1";
"B"
$PN"2"23;
"A"
$PN"1"17;
%"UNIVERSAL_POWER"
"1","(4075,775)","2","logical_power","I116";
;
HDL_POWER"P3V_BAT_R"
CDS_LIB"logical_power";
"A"2;
%"Q_RES"
"1","(4200,-1175)","0","pure_quanta","I118";
;
PART_NUMBER"CS00002JB13"
WATTAGE"1/16W"
PACK_TYPE"0402LF"
MATERIAL"CHIP"
VALUE"0"
TOLERANCE"5%"
LOCATION"R915"
CDS_LIB"pure_quanta"
$SEC"1"
CDS_SEC"1";
"B"
$PN"2"22;
"A"
$PN"1"25;
%"Q_RES"
"1","(4200,-1250)","0","pure_quanta","I119";
;
PART_NUMBER"CS00002JB13"
WATTAGE"1/16W"
PACK_TYPE"0402LF"
VALUE"0"
TOLERANCE"5%"
MATERIAL"CHIP"
LOCATION"R916"
CDS_LIB"pure_quanta"
$SEC"1"
CDS_SEC"1";
"B"
$PN"2"21;
"A"
$PN"1"24;
%"Q_RES"
"1","(4200,-1325)","0","pure_quanta","I120";
;
PART_NUMBER"CS00002JB13"
MATERIAL"CHIP"
TOLERANCE"5%"
VALUE"0"
WATTAGE"1/16W"
PACK_TYPE"0402LF"
LOCATION"R918"
CDS_LIB"pure_quanta"
$SEC"1"
CDS_SEC"1";
"B"
$PN"2"19;
"A"
$PN"1"18;
%"Q_RES"
"1","(4200,-1400)","0","pure_quanta","I121";
;
PART_NUMBER"CS00002JB13"
PACK_TYPE"0402LF"
WATTAGE"1/16W"
TOLERANCE"5%"
VALUE"0"
MATERIAL"CHIP"
LOCATION"R917"
CDS_LIB"pure_quanta"
$SEC"1"
CDS_SEC"1";
"B"
$PN"2"20;
"A"
$PN"1"16;
%"MOSFET_NCH_GDS_ESD_PROTECTED"
"1","(25,-400)","0","pure_quanta","I123";
;
PART_NUMBER"BAM70020002"
PART_TYPE"SMLF"
VALUE"2N7002K"
MATERIAL"IC"
LOCATION"Q34"
CDS_LIB"pure_quanta"
CDS_LMAN_SYM_OUTLINE"-125,150,125,-150"
NEEDS_NO_SIZE"TRUE"
$SEC"1"
CDS_SEC"1";
"S"
$PN"S"6;
"G"
$PN"G"14;
"D"
$PN"D"28;
%"MOSFET_NCH_GDS_ESD_PROTECTED"
"1","(25,-1300)","0","pure_quanta","I124";
;
PART_NUMBER"BAM70020002"
MATERIAL"IC"
PART_TYPE"SMLF"
VALUE"2N7002K"
LOCATION"Q35"
NEEDS_NO_SIZE"TRUE"
CDS_LMAN_SYM_OUTLINE"-125,150,125,-150"
CDS_LIB"pure_quanta"
$SEC"1"
CDS_SEC"1";
"S"
$PN"S"7;
"G"
$PN"G"13;
"D"
$PN"D"15;
%"Q_RES"
"2","(-1125,-625)","0","pure_quanta","I125";
;
PART_NUMBER"CS41002FB09"
TOLERANCE"1%"
VALUE"100K"
WATTAGE"1/16W"
MATERIAL"CHIP"
PACK_TYPE"0402LF"
$LOCATION"R4712"
CDS_LIB"pure_quanta"
CDS_LOCATION"R4712"
$SEC"1"
CDS_SEC"1";
"A"
$PN"1"14;
"B"
$PN"2"11;
%"UNIVERSAL_GND"
"1","(-1125,-875)","0","logical_power","I126";
;
HDL_POWER"GND"
ROOM"IO_SLOT"
CDS_LIB"logical_power";
"A"11;
%"Q_RES"
"2","(-1125,-1525)","0","pure_quanta","I127";
;
PART_NUMBER"CS41002FB09"
VALUE"100K"
PACK_TYPE"0402LF"
TOLERANCE"1%"
WATTAGE"1/16W"
MATERIAL"CHIP"
$LOCATION"R4713"
CDS_LIB"pure_quanta"
CDS_LOCATION"R4713"
$SEC"1"
CDS_SEC"1";
"A"
$PN"1"13;
"B"
$PN"2"12;
%"UNIVERSAL_GND"
"1","(-1125,-1775)","0","logical_power","I128";
;
HDL_POWER"GND"
ROOM"IO_SLOT"
CDS_LIB"logical_power";
"A"12;
%"Q_RES"
"2","(3625,3550)","0","pure_quanta","I24";
;
PART_NUMBER"CS31002FB08"
PACK_TYPE"0402LF"
MATERIAL"CHIP"
WATTAGE"1/16W"
VALUE"10K"
TOLERANCE"1%"
$LOCATION"R498"
CDS_LIB"pure_quanta"
CDS_LOCATION"R498"
$SEC"1"
CDS_SEC"1";
"A"
$PN"1"3;
"B"
$PN"2"53;
%"UNIVERSAL_POWER"
"1","(3625,3775)","0","logical_power","I25";
;
HDL_POWER"P3V3_AUX"
CDS_LIB"logical_power";
"A"3;
%"EMMITSBURG_REV0P9"
"7","(1125,2675)","0","pure_quanta","I27";
;
PART_NUMBER"AJ0QV2N0T00"
PART_TYPE"SMLF"
VALUE"GFNOCPU04302300-QV2N-MM#99A1WT"
MATERIAL"IC"
$LOCATION"U4"
CDS_LIB"pure_quanta"
CDS_LMAN_SYM_OUTLINE"-1475,775,1475,-775"
NEEDS_NO_SIZE"TRUE"
CDS_LOCATION"U4"
$SEC"7"
CDS_SEC"7";
"VSS_A41"
$PN"A41"53;
"SRTCRST_N \B"
$PN"BF9"44;
"SPI0_TPM_CS_N \B"
$PN"BB11"39;
"SPI0_MISO_IO_1"
$PN"AW16"30;
"SPI0_MOSI_IO_0"
$PN"BA13"41;
"SPI0_IO_3"
$PN"BA16"29;
"SPI0_IO_2"
$PN"AV15"43;
"SPI0_FLASH_1_CS_N \B"
$PN"BA10"38;
"SPI0_FLASH_0_CS_N \B"
$PN"AW13"42;
"SPI0_CLK"
$PN"BB15"37;
"RCTRST_N \B"
$PN"BD7"40;
"NC_CGC_DUT_DETECT_N \B"
$PN"BG3"52;
"GPP_N_4"
$PN"V11"51;
"GPP_N_1"
$PN"T11"50;
"GPPC_S_9_SMI_N \B"
$PN"AV18"57;
"GPPC_S_8_NMI_N \B"
$PN"AP15"58;
"GPPC_S_7_SUSACK_N \B"
$PN"BA7"59;
"GPPC_S_6_SUSWARN_N_SUSPWRDNACK"
$PN"AR13"60;
"GPPC_S_5_CPU_GP_3"
$PN"AT18"36;
"GPPC_S_4_CPU_GP_2"
$PN"AU13"35;
"GPPC_S_3_CPU_GP_1"
$PN"AV11"34;
"GPPC_S_2_CPU_GP_0"
$PN"AR16"33;
"GPPC_S_1_SPKR_TIME_SYNC_1"
$PN"AU16"32;
"GPPC_S_11"
$PN"BB8"55;
"GPPC_S_10"
$PN"AW10"56;
"GPPC_S_0_TIME_SYNC_0"
$PN"BB18"31;
%"UNIVERSAL_POWER"
"1","(-1400,1300)","2","logical_power","I53";
;
HDL_POWER"P3V3_RTC_AUX"
CDS_LIB"logical_power";
"A"4;
%"UNIVERSAL_POWER"
"1","(4500,900)","2","logical_power","I56";
;
HDL_POWER"P3V3_AUX"
CDS_LIB"logical_power";
"A"5;
%"UNIVERSAL_POWER"
"1","(5125,600)","2","logical_power","I59";
;
HDL_POWER"P3V3_RTC_AUX"
CDS_LIB"logical_power";
"A"1;
%"Q_RES"
"1","(3625,350)","0","pure_quanta","I62";
;
PART_NUMBER"CS21002FB06"
WATTAGE"1/16W"
PACK_TYPE"0402LF"
MATERIAL"CHIP"
VALUE"1K"
TOLERANCE"1%"
$LOCATION"R1203"
CDS_LIB"pure_quanta"
CDS_LOCATION"R1203"
$SEC"1"
CDS_SEC"1";
"B"
$PN"2"2;
"A"
$PN"1"27;
%"CONN2_AAABAT029Y19"
"1","(2725,350)","2","pure_quanta","I63";
;
PART_NUMBER"DFHS02FR062"
VALUE"CONN2_AAA-BAT-029-Y19"
PART_TYPE"THLF"
MATERIAL"IO"
$LOCATION"BT1"
CDS_LIB"pure_quanta"
CDS_LMAN_SYM_OUTLINE"-50,50,50,-50"
NEEDS_NO_SIZE"TRUE"
CDS_LOCATION"BT1"
$SEC"1"
CDS_SEC"1";
"2"
$PN"2"10;
"1"
$PN"1"27;
%"BAS70057F"
"1","(4700,400)","7","pure_quanta","I64";
;
PART_NUMBER"BC0BAS70Z01"
VALUE"BAS70-05-7-F"
PART_TYPE"SMLF"
MATERIAL"IC"
$LOCATION"U62"
NEEDS_NO_SIZE"TRUE"
CDS_LMAN_SYM_OUTLINE"-75,50,75,-25"
CDS_LIB"pure_quanta"
CDS_LOCATION"U62"
$SEC"1"
CDS_SEC"1";
"C"
$PN"3"1;
"A"
$PN"2"5;
"B"
$PN"1"2;
%"Q_CAP"
"1","(5125,150)","0","pure_quanta","I65";
;
PART_NUMBER"CH5104KEB02"
TOLERANCE"10%"
VOLTAGE"25V"
VALUE"1UF"
MATERIAL"X6S"
PACK_TYPE"C0402"
$LOCATION"C611"
CDS_LIB"pure_quanta"
CDS_LOCATION"C611"
$SEC"1"
CDS_SEC"1";
"B"
$PN"2"8;
"A"
$PN"1"1;
%"UNIVERSAL_GND"
"1","(2400,150)","0","logical_power","I66";
;
ROOM"IO_SLOT"
HDL_POWER"GND"
CDS_LIB"logical_power";
"A"10;
%"UNIVERSAL_GND"
"1","(5125,-75)","0","logical_power","I67";
;
ROOM"IO_SLOT"
HDL_POWER"GND"
CDS_LIB"logical_power";
"A"8;
%"Q_CAP"
"1","(-1400,675)","0","pure_quanta","I68";
;
PART_NUMBER"CH5104KEB02"
VOLTAGE"25V"
MATERIAL"X6S"
TOLERANCE"10%"
VALUE"1UF"
PACK_TYPE"C0402"
$LOCATION"C610"
CDS_LIB"pure_quanta"
CDS_LOCATION"C610"
$SEC"1"
CDS_SEC"1";
"B"
$PN"2"9;
"A"
$PN"1"54;
%"UNIVERSAL_GND"
"1","(-1400,425)","0","logical_power","I69";
;
ROOM"IO_SLOT"
HDL_POWER"GND"
CDS_LIB"logical_power";
"A"9;
%"Q_RES"
"2","(-1400,1075)","0","pure_quanta","I70";
;
PART_NUMBER"CS32002FB06"
TOLERANCE"1%"
VALUE"20K"
MATERIAL"CHIP"
PACK_TYPE"0402LF"
WATTAGE"1/16W"
$LOCATION"R1202"
CDS_LIB"pure_quanta"
CDS_LOCATION"R1202"
$SEC"1"
CDS_SEC"1";
"A"
$PN"1"4;
"B"
$PN"2"54;
%"Q_RES"
"1","(4225,-500)","0","pure_quanta","I80";
;
PART_NUMBER"CS00002JB13"
PACK_TYPE"0402LF"
MATERIAL"CHIP"
VALUE"0"
WATTAGE"1/16W"
TOLERANCE"5%"
$LOCATION"R1461"
CDS_LIB"pure_quanta"
CDS_LOCATION"R1461"
$SEC"1"
CDS_SEC"1";
"B"
$PN"2"49;
"A"
$PN"1"46;
%"UNIVERSAL_GND"
"1","(50,-775)","0","logical_power","I83";
;
CDS_LIB"logical_power"
HDL_POWER"GND"
ROOM"IO_SLOT";
"A"6;
%"Q_RES"
"1","(-350,-25)","0","pure_quanta","I85";
;
PART_NUMBER"CS00002JB13"
MATERIAL"EMPTY"
PACK_TYPE"0402LF"
TOLERANCE"5%"
VALUE"0"
WATTAGE"1/16W"
$LOCATION"R1839"
CDS_LIB"pure_quanta"
CDS_LOCATION"R1839"
$SEC"1"
CDS_SEC"1";
"B"
$PN"2"28;
"A"
$PN"1"14;
%"UNIVERSAL_GND"
"1","(50,-1675)","0","logical_power","I88";
;
CDS_LIB"logical_power"
HDL_POWER"GND"
ROOM"IO_SLOT";
"A"7;
%"Q_RES"
"1","(-350,-925)","0","pure_quanta","I89";
;
PART_NUMBER"CS00002JB13"
VALUE"0"
MATERIAL"EMPTY"
PACK_TYPE"0402LF"
TOLERANCE"5%"
WATTAGE"1/16W"
$LOCATION"R1840"
CDS_LIB"pure_quanta"
CDS_LOCATION"R1840"
$SEC"1"
CDS_SEC"1";
"B"
$PN"2"15;
"A"
$PN"1"13;
END.
